(kicad_pcb
	(version 20260206)
	(generator "pcbnew")
	(generator_version "10.0")
	(general
		(thickness 1.6)
		(legacy_teardrops no)
	)
	(paper "A4")
	(title_block
		(title "peb — Lightning_PEB_BRD.brd")
		(comment 1 "Lightning (Wiwynn / Facebook NVMe JBOF) / footprints 739-745 of 2563")
	)
	(layers
		(0 "F.Cu" signal "TOP")
		(4 "In1.Cu" signal "L2GND")
		(6 "In2.Cu" signal "L3")
		(8 "In3.Cu" signal "L4VCC")
		(10 "In4.Cu" signal "L5VCC")
		(12 "In5.Cu" signal "L6")
		(14 "In6.Cu" signal "L7GND")
		(2 "B.Cu" signal "BOTTOM")
		(9 "F.Adhes" user "F.Adhesive")
		(11 "B.Adhes" user "B.Adhesive")
		(13 "F.Paste" user "Package Geometry/Pastemask Top")
		(15 "B.Paste" user "Package Geometry/Pastemask Bottom")
		(5 "F.SilkS" user "Ref Des/Silkscreen Top")
		(7 "B.SilkS" user "Ref Des/Silkscreen Bottom")
		(1 "F.Mask" user "Board Geometry/Soldermask Top")
		(3 "B.Mask" user "Board Geometry/Soldermask Bottom")
		(17 "Dwgs.User" user "User.Drawings")
		(19 "Cmts.User" user "User.Comments")
		(21 "Eco1.User" user "User.Eco1")
		(23 "Eco2.User" user "User.Eco2")
		(25 "Edge.Cuts" user "Board Geometry/Outline")
		(27 "Margin" user)
		(31 "F.CrtYd" user "Package Geometry/Place Bound Top")
		(29 "B.CrtYd" user "Package Geometry/Place Bound Bottom")
		(35 "F.Fab" user "Ref Des/Assembly Top")
		(33 "B.Fab" user "Ref Des/Assembly Bottom")
	)
	(footprint ""
		(layer "F.Cu")
		(at 168.021 -86.3854 90)
		(property "Reference" "R45"
			(at 0 0 90)
			(layer "F.SilkS")
			(hide yes)
			(effects
				(font
					(size 1.27 1.27)
				)
			)
		)
		(property "Value" "10KR2F-2-GP"
			(at 0.064008 -3.993896 90)
			(unlocked yes)
			(layer "F.Fab")
			(hide yes)
			(effects
				(font
					(size 1.016 1.016)
					(thickness 0.1524)
				)
			)
		)
		(property "Device Type" "R402H16"
			(at 0.064008 -5.517896 90)
			(unlocked yes)
			(layer "F.Fab")
			(hide yes)
			(effects
				(font
					(size 1.016 1.016)
					(thickness 0.1524)
				)
			)
		)
		(duplicate_pad_numbers_are_jumpers no)
		(fp_line
			(start 0.508 -0.9398)
			(end -0.508 -0.9398)
			(stroke
				(width 0.1524)
				(type default)
			)
			(layer "F.SilkS")
		)
		(fp_line
			(start -0.508 -0.9398)
			(end -0.508 0.9398)
			(stroke
				(width 0.1524)
				(type default)
			)
			(layer "F.SilkS")
		)
		(fp_rect
			(start -0.508 0.9398)
			(end 0.508 -0.9398)
			(stroke
				(width 0)
				(type default)
			)
			(fill no)
			(layer "F.CrtYd")
		)
		(fp_rect
			(start -0.508 0.9398)
			(end 0.508 -0.9398)
			(stroke
				(width 0)
				(type default)
			)
			(fill no)
			(layer "F.Fab")
		)
		(pad "1" smd custom
			(at 0 -0.4445 90)
			(size 0.1397 0.1397)
			(layers "F.Cu" "F.Mask" "F.Paste")
			(net "CLKGEN_OE1")
			(options
				(clearance outline)
				(anchor circle)
			)
			(primitives
				(gr_poly
					(pts
						(arc
							(start -0.1778 -0.2794)
							(mid -0.249642 -0.249642)
							(end -0.2794 -0.1778)
						)
						(arc
							(start -0.2794 0.1778)
							(mid -0.249642 0.249642)
							(end -0.1778 0.2794)
						)
						(arc
							(start 0.1778 0.2794)
							(mid 0.249642 0.249642)
							(end 0.2794 0.1778)
						)
						(arc
							(start 0.2794 -0.1778)
							(mid 0.249642 -0.249642)
							(end 0.1778 -0.2794)
						)
					)
					(width 0)
					(fill yes)
				)
			)
		)
		(pad "2" smd custom
			(at 0 0.4445 90)
			(size 0.1397 0.1397)
			(layers "F.Cu" "F.Mask" "F.Paste")
			(net "P1V8_CLKGEN")
			(options
				(clearance outline)
				(anchor circle)
			)
			(primitives
				(gr_poly
					(pts
						(arc
							(start -0.1778 -0.2794)
							(mid -0.249642 -0.249642)
							(end -0.2794 -0.1778)
						)
						(arc
							(start -0.2794 0.1778)
							(mid -0.249642 0.249642)
							(end -0.1778 0.2794)
						)
						(arc
							(start 0.1778 0.2794)
							(mid 0.249642 0.249642)
							(end 0.2794 0.1778)
						)
						(arc
							(start 0.2794 -0.1778)
							(mid 0.249642 -0.249642)
							(end 0.1778 -0.2794)
						)
					)
					(width 0)
					(fill yes)
				)
			)
		)
	)
	(footprint ""
		(layer "F.Cu")
		(at 47.350172 -50.306224 180)
		(property "Reference" "R497"
			(at 0 0 180)
			(layer "F.SilkS")
			(hide yes)
			(effects
				(font
					(size 1.27 1.27)
				)
			)
		)
		(property "Value" "33K2R2F-GP"
			(at 0.064008 -3.993896 180)
			(unlocked yes)
			(layer "F.Fab")
			(hide yes)
			(effects
				(font
					(size 1.016 1.016)
					(thickness 0.1524)
				)
			)
		)
		(property "Device Type" "R402H16"
			(at 0.064008 -5.517896 180)
			(unlocked yes)
			(layer "F.Fab")
			(hide yes)
			(effects
				(font
					(size 1.016 1.016)
					(thickness 0.1524)
				)
			)
		)
		(duplicate_pad_numbers_are_jumpers no)
		(fp_line
			(start 0.508 -0.9398)
			(end -0.508 -0.9398)
			(stroke
				(width 0.1524)
				(type default)
			)
			(layer "F.SilkS")
		)
		(fp_line
			(start -0.508 -0.9398)
			(end -0.508 0.9398)
			(stroke
				(width 0.1524)
				(type default)
			)
			(layer "F.SilkS")
		)
		(fp_rect
			(start -0.508 0.9398)
			(end 0.508 -0.9398)
			(stroke
				(width 0)
				(type default)
			)
			(fill no)
			(layer "F.CrtYd")
		)
		(fp_rect
			(start -0.508 0.9398)
			(end 0.508 -0.9398)
			(stroke
				(width 0)
				(type default)
			)
			(fill no)
			(layer "F.Fab")
		)
		(pad "1" smd custom
			(at 0 -0.4445 180)
			(size 0.1397 0.1397)
			(layers "F.Cu" "F.Mask" "F.Paste")
			(net "P3V3_STBY")
			(options
				(clearance outline)
				(anchor circle)
			)
			(primitives
				(gr_poly
					(pts
						(arc
							(start -0.1778 -0.2794)
							(mid -0.249642 -0.249642)
							(end -0.2794 -0.1778)
						)
						(arc
							(start -0.2794 0.1778)
							(mid -0.249642 0.249642)
							(end -0.1778 0.2794)
						)
						(arc
							(start 0.1778 0.2794)
							(mid 0.249642 0.249642)
							(end 0.2794 0.1778)
						)
						(arc
							(start 0.2794 -0.1778)
							(mid 0.249642 -0.249642)
							(end 0.1778 -0.2794)
						)
					)
					(width 0)
					(fill yes)
				)
			)
		)
		(pad "2" smd custom
			(at 0 0.4445 180)
			(size 0.1397 0.1397)
			(layers "F.Cu" "F.Mask" "F.Paste")
			(net "NVM_SI_R")
			(options
				(clearance outline)
				(anchor circle)
			)
			(primitives
				(gr_poly
					(pts
						(arc
							(start -0.1778 -0.2794)
							(mid -0.249642 -0.249642)
							(end -0.2794 -0.1778)
						)
						(arc
							(start -0.2794 0.1778)
							(mid -0.249642 0.249642)
							(end -0.1778 0.2794)
						)
						(arc
							(start 0.1778 0.2794)
							(mid 0.249642 0.249642)
							(end 0.2794 0.1778)
						)
						(arc
							(start 0.2794 -0.1778)
							(mid 0.249642 -0.249642)
							(end 0.1778 -0.2794)
						)
					)
					(width 0)
					(fill yes)
				)
			)
		)
	)
	(footprint ""
		(layer "F.Cu")
		(at 64.3636 -114.0968)
		(property "Reference" "R487"
			(at 0 0 0)
			(layer "F.SilkS")
			(hide yes)
			(effects
				(font
					(size 1.27 1.27)
				)
			)
		)
		(property "Value" "0R2J-2-GP"
			(at 0.064008 -3.993896 0)
			(unlocked yes)
			(layer "F.Fab")
			(hide yes)
			(effects
				(font
					(size 1.016 1.016)
					(thickness 0.1524)
				)
			)
		)
		(property "Device Type" "R402H16"
			(at 0.064008 -5.517896 0)
			(unlocked yes)
			(layer "F.Fab")
			(hide yes)
			(effects
				(font
					(size 1.016 1.016)
					(thickness 0.1524)
				)
			)
		)
		(duplicate_pad_numbers_are_jumpers no)
		(fp_line
			(start -0.508 -0.9398)
			(end -0.508 0.9398)
			(stroke
				(width 0.1524)
				(type default)
			)
			(layer "F.SilkS")
		)
		(fp_line
			(start 0.508 -0.9398)
			(end -0.508 -0.9398)
			(stroke
				(width 0.1524)
				(type default)
			)
			(layer "F.SilkS")
		)
		(fp_rect
			(start -0.508 0.9398)
			(end 0.508 -0.9398)
			(stroke
				(width 0)
				(type default)
			)
			(fill no)
			(layer "F.CrtYd")
		)
		(fp_rect
			(start -0.508 0.9398)
			(end 0.508 -0.9398)
			(stroke
				(width 0)
				(type default)
			)
			(fill no)
			(layer "F.Fab")
		)
		(pad "1" smd custom
			(at 0 -0.4445)
			(size 0.1397 0.1397)
			(layers "F.Cu" "F.Mask" "F.Paste")
			(net "BMC0_SDA11_R")
			(options
				(clearance outline)
				(anchor circle)
			)
			(primitives
				(gr_poly
					(pts
						(arc
							(start -0.1778 -0.2794)
							(mid -0.249642 -0.249642)
							(end -0.2794 -0.1778)
						)
						(arc
							(start -0.2794 0.1778)
							(mid -0.249642 0.249642)
							(end -0.1778 0.2794)
						)
						(arc
							(start 0.1778 0.2794)
							(mid 0.249642 0.249642)
							(end 0.2794 0.1778)
						)
						(arc
							(start 0.2794 -0.1778)
							(mid 0.249642 -0.249642)
							(end 0.1778 -0.2794)
						)
					)
					(width 0)
					(fill yes)
				)
			)
		)
		(pad "2" smd custom
			(at 0 0.4445)
			(size 0.1397 0.1397)
			(layers "F.Cu" "F.Mask" "F.Paste")
			(net "BMC_I2C11_MINI5_SDA_S")
			(options
				(clearance outline)
				(anchor circle)
			)
			(primitives
				(gr_poly
					(pts
						(arc
							(start -0.1778 -0.2794)
							(mid -0.249642 -0.249642)
							(end -0.2794 -0.1778)
						)
						(arc
							(start -0.2794 0.1778)
							(mid -0.249642 0.249642)
							(end -0.1778 0.2794)
						)
						(arc
							(start 0.1778 0.2794)
							(mid 0.249642 0.249642)
							(end 0.2794 0.1778)
						)
						(arc
							(start 0.2794 -0.1778)
							(mid 0.249642 -0.249642)
							(end 0.1778 -0.2794)
						)
					)
					(width 0)
					(fill yes)
				)
			)
		)
	)
	(footprint ""
		(layer "F.Cu")
		(at 229.108 -88.9 -90)
		(property "Reference" "R586"
			(at 0 0 270)
			(layer "F.SilkS")
			(hide yes)
			(effects
				(font
					(size 1.27 1.27)
				)
			)
		)
		(property "Value" "4K7R2F-GP"
			(at 0.064008 -3.993896 270)
			(unlocked yes)
			(layer "F.Fab")
			(hide yes)
			(effects
				(font
					(size 1.016 1.016)
					(thickness 0.1524)
				)
			)
		)
		(property "Device Type" "R402H16"
			(at 0.064008 -5.517896 270)
			(unlocked yes)
			(layer "F.Fab")
			(hide yes)
			(effects
				(font
					(size 1.016 1.016)
					(thickness 0.1524)
				)
			)
		)
		(duplicate_pad_numbers_are_jumpers no)
		(fp_line
			(start -0.508 -0.9398)
			(end -0.508 0.9398)
			(stroke
				(width 0.1524)
				(type default)
			)
			(layer "F.SilkS")
		)
		(fp_line
			(start 0.508 -0.9398)
			(end -0.508 -0.9398)
			(stroke
				(width 0.1524)
				(type default)
			)
			(layer "F.SilkS")
		)
		(fp_rect
			(start -0.508 0.9398)
			(end 0.508 -0.9398)
			(stroke
				(width 0)
				(type default)
			)
			(fill no)
			(layer "F.CrtYd")
		)
		(fp_rect
			(start -0.508 0.9398)
			(end 0.508 -0.9398)
			(stroke
				(width 0)
				(type default)
			)
			(fill no)
			(layer "F.Fab")
		)
		(pad "1" smd custom
			(at 0 -0.4445 270)
			(size 0.1397 0.1397)
			(layers "F.Cu" "F.Mask" "F.Paste")
			(net "P3V3_STBY")
			(options
				(clearance outline)
				(anchor circle)
			)
			(primitives
				(gr_poly
					(pts
						(arc
							(start -0.1778 -0.2794)
							(mid -0.249642 -0.249642)
							(end -0.2794 -0.1778)
						)
						(arc
							(start -0.2794 0.1778)
							(mid -0.249642 0.249642)
							(end -0.1778 0.2794)
						)
						(arc
							(start 0.1778 0.2794)
							(mid 0.249642 0.249642)
							(end 0.2794 0.1778)
						)
						(arc
							(start 0.2794 -0.1778)
							(mid 0.249642 -0.249642)
							(end 0.1778 -0.2794)
						)
					)
					(width 0)
					(fill yes)
				)
			)
		)
		(pad "2" smd custom
			(at 0 0.4445 270)
			(size 0.1397 0.1397)
			(layers "F.Cu" "F.Mask" "F.Paste")
			(net "TEMP_3_A1")
			(options
				(clearance outline)
				(anchor circle)
			)
			(primitives
				(gr_poly
					(pts
						(arc
							(start -0.1778 -0.2794)
							(mid -0.249642 -0.249642)
							(end -0.2794 -0.1778)
						)
						(arc
							(start -0.2794 0.1778)
							(mid -0.249642 0.249642)
							(end -0.1778 0.2794)
						)
						(arc
							(start 0.1778 0.2794)
							(mid 0.249642 0.249642)
							(end 0.2794 0.1778)
						)
						(arc
							(start 0.2794 -0.1778)
							(mid 0.249642 -0.249642)
							(end 0.1778 -0.2794)
						)
					)
					(width 0)
					(fill yes)
				)
			)
		)
	)
	(footprint ""
		(layer "F.Cu")
		(at 85.5726 -56.388 -90)
		(property "Reference" "R339"
			(at 0 0 270)
			(layer "F.SilkS")
			(hide yes)
			(effects
				(font
					(size 1.27 1.27)
				)
			)
		)
		(property "Value" "3K3R2F-2-GP"
			(at 0.064008 -3.993896 270)
			(unlocked yes)
			(layer "F.Fab")
			(hide yes)
			(effects
				(font
					(size 1.016 1.016)
					(thickness 0.1524)
				)
			)
		)
		(property "Device Type" "R402H16"
			(at 0.064008 -5.517896 270)
			(unlocked yes)
			(layer "F.Fab")
			(hide yes)
			(effects
				(font
					(size 1.016 1.016)
					(thickness 0.1524)
				)
			)
		)
		(duplicate_pad_numbers_are_jumpers no)
		(fp_line
			(start -0.508 -0.9398)
			(end -0.508 0.9398)
			(stroke
				(width 0.1524)
				(type default)
			)
			(layer "F.SilkS")
		)
		(fp_line
			(start 0.508 -0.9398)
			(end -0.508 -0.9398)
			(stroke
				(width 0.1524)
				(type default)
			)
			(layer "F.SilkS")
		)
		(fp_rect
			(start -0.508 0.9398)
			(end 0.508 -0.9398)
			(stroke
				(width 0)
				(type default)
			)
			(fill no)
			(layer "F.CrtYd")
		)
		(fp_rect
			(start -0.508 0.9398)
			(end 0.508 -0.9398)
			(stroke
				(width 0)
				(type default)
			)
			(fill no)
			(layer "F.Fab")
		)
		(pad "1" smd custom
			(at 0 -0.4445 270)
			(size 0.1397 0.1397)
			(layers "F.Cu" "F.Mask" "F.Paste")
			(net "AS_ROMA0_R")
			(options
				(clearance outline)
				(anchor circle)
			)
			(primitives
				(gr_poly
					(pts
						(arc
							(start -0.1778 -0.2794)
							(mid -0.249642 -0.249642)
							(end -0.2794 -0.1778)
						)
						(arc
							(start -0.2794 0.1778)
							(mid -0.249642 0.249642)
							(end -0.1778 0.2794)
						)
						(arc
							(start 0.1778 0.2794)
							(mid 0.249642 0.249642)
							(end 0.2794 0.1778)
						)
						(arc
							(start 0.2794 -0.1778)
							(mid 0.249642 -0.249642)
							(end 0.1778 -0.2794)
						)
					)
					(width 0)
					(fill yes)
				)
			)
		)
		(pad "2" smd custom
			(at 0 0.4445 270)
			(size 0.1397 0.1397)
			(layers "F.Cu" "F.Mask" "F.Paste")
			(net "P3V3_STBY")
			(options
				(clearance outline)
				(anchor circle)
			)
			(primitives
				(gr_poly
					(pts
						(arc
							(start -0.1778 -0.2794)
							(mid -0.249642 -0.249642)
							(end -0.2794 -0.1778)
						)
						(arc
							(start -0.2794 0.1778)
							(mid -0.249642 0.249642)
							(end -0.1778 0.2794)
						)
						(arc
							(start 0.1778 0.2794)
							(mid 0.249642 0.249642)
							(end 0.2794 0.1778)
						)
						(arc
							(start 0.2794 -0.1778)
							(mid 0.249642 -0.249642)
							(end 0.1778 -0.2794)
						)
					)
					(width 0)
					(fill yes)
				)
			)
		)
	)
	(footprint ""
		(layer "F.Cu")
		(at 224.79 -9.779 -90)
		(property "Reference" "U10"
			(at 0 0 270)
			(layer "F.SilkS")
			(hide yes)
			(effects
				(font
					(size 1.27 1.27)
				)
			)
		)
		(property "Value" "CAT24C128WI-GT3-GP"
			(at -3.707384 -1.5367 270)
			(unlocked yes)
			(layer "F.Fab")
			(hide yes)
			(effects
				(font
					(size 1.016 1.016)
					(thickness 0.1524)
				)
			)
		)
		(property "Device Type" "SOIC8H69"
			(at -3.707384 -3.0607 270)
			(unlocked yes)
			(layer "F.Fab")
			(hide yes)
			(effects
				(font
					(size 1.016 1.016)
					(thickness 0.1524)
				)
			)
		)
		(duplicate_pad_numbers_are_jumpers no)
		(fp_line
			(start -2.6289 3.4417)
			(end -2.6289 1.4732)
			(stroke
				(width 0.381)
				(type default)
			)
			(layer "F.SilkS")
		)
		(fp_line
			(start -2.7432 1.4224)
			(end -2.6416 1.4224)
			(stroke
				(width 0.1524)
				(type default)
			)
			(layer "F.SilkS")
		)
		(fp_line
			(start -2.7432 1.4224)
			(end 2.1336 1.4224)
			(stroke
				(width 0.1524)
				(type default)
			)
			(layer "F.SilkS")
		)
		(fp_line
			(start 2.1336 1.4224)
			(end 2.1336 -1.4224)
			(stroke
				(width 0.1524)
				(type default)
			)
			(layer "F.SilkS")
		)
		(fp_line
			(start -2.1844 -0.0508)
			(end -2.7178 0.508)
			(stroke
				(width 0.1524)
				(type default)
			)
			(layer "F.SilkS")
		)
		(fp_line
			(start -2.7178 -0.508)
			(end -2.1844 -0.0508)
			(stroke
				(width 0.1524)
				(type default)
			)
			(layer "F.SilkS")
		)
		(fp_line
			(start -2.7432 -1.4224)
			(end -2.7432 1.4224)
			(stroke
				(width 0.1524)
				(type default)
			)
			(layer "F.SilkS")
		)
		(fp_line
			(start 2.1336 -1.4224)
			(end -2.7432 -1.4224)
			(stroke
				(width 0.1524)
				(type default)
			)
			(layer "F.SilkS")
		)
		(fp_poly
			(pts
				(xy -2.2098 -1.4224) (xy -2.2098 1.4224) (xy 2.2098 1.4224) (xy 2.2098 -1.4224)
			)
			(stroke
				(width 0)
				(type default)
			)
			(fill yes)
			(layer "F.SilkS")
		)
		(fp_rect
			(start -2.450084 2.999994)
			(end 2.450084 -2.999994)
			(stroke
				(width 0)
				(type default)
			)
			(fill no)
			(layer "F.CrtYd")
		)
		(fp_poly
			(pts
				(xy -2.8194 3.6322) (xy -2.8194 -3.6322) (xy 2.8194 -3.6322) (xy 2.8194 1.18364) (xy 2.450084 1.18364)
				(xy 2.450084 -2.999994) (xy -2.450084 -2.999994) (xy -2.450084 2.999994) (xy 2.450084 2.999994)
				(xy 2.450084 1.18618) (xy 2.8194 1.18618) (xy 2.8194 3.6322)
			)
			(stroke
				(width 0)
				(type default)
			)
			(fill no)
			(layer "F.CrtYd")
		)
		(fp_rect
			(start -2.8194 3.6322)
			(end 2.8194 -3.6322)
			(stroke
				(width 0)
				(type default)
			)
			(fill no)
			(layer "F.Fab")
		)
		(pad "1" smd rect
			(at -1.905 2.54 270)
			(size 0.635 1.651)
			(layers "F.Cu" "F.Mask" "F.Paste")
			(net "EEPROM_A0")
		)
		(pad "2" smd rect
			(at -0.635 2.54 270)
			(size 0.635 1.651)
			(layers "F.Cu" "F.Mask" "F.Paste")
			(net "EEPROM_A1")
		)
		(pad "3" smd rect
			(at 0.635 2.54 270)
			(size 0.635 1.651)
			(layers "F.Cu" "F.Mask" "F.Paste")
			(net "EEPROM_A2")
		)
		(pad "4" smd rect
			(at 1.905 2.54 270)
			(size 0.635 1.651)
			(layers "F.Cu" "F.Mask" "F.Paste")
			(net "GND")
		)
		(pad "5" smd rect
			(at 1.905 -2.54 270)
			(size 0.635 1.651)
			(layers "F.Cu" "F.Mask" "F.Paste")
			(net "TWI_SDA2_R")
		)
		(pad "6" smd rect
			(at 0.635 -2.54 270)
			(size 0.635 1.651)
			(layers "F.Cu" "F.Mask" "F.Paste")
			(net "TWI_SCL2_R")
		)
		(pad "7" smd rect
			(at -0.635 -2.54 270)
			(size 0.635 1.651)
			(layers "F.Cu" "F.Mask" "F.Paste")
			(net "EEPROM_WP_8536")
		)
		(pad "8" smd rect
			(at -1.905 -2.54 270)
			(size 0.635 1.651)
			(layers "F.Cu" "F.Mask" "F.Paste")
			(net "P3V3_STBY")
		)
	)
	(footprint ""
		(layer "F.Cu")
		(at 28.2956 -184.0992)
		(property "Reference" "C261"
			(at 0 0 0)
			(layer "F.SilkS")
			(hide yes)
			(effects
				(font
					(size 1.27 1.27)
				)
			)
		)
		(property "Value" "SC220P50V3JN-GP"
			(at 0 -2.8194 0)
			(unlocked yes)
			(layer "F.Fab")
			(hide yes)
			(effects
				(font
					(size 1.016 1.016)
					(thickness 0.1524)
				)
			)
		)
		(property "Device Type" "C603H36"
			(at 0 -4.3434 0)
			(unlocked yes)
			(layer "F.Fab")
			(hide yes)
			(effects
				(font
					(size 1.016 1.016)
					(thickness 0.1524)
				)
			)
		)
		(duplicate_pad_numbers_are_jumpers no)
		(fp_line
			(start 0.508 0)
			(end -0.508 0)
			(stroke
				(width 0.2032)
				(type default)
			)
			(layer "F.SilkS")
		)
		(fp_rect
			(start -0.5842 1.3335)
			(end 0.5842 -1.3335)
			(stroke
				(width 0)
				(type default)
			)
			(fill no)
			(layer "F.CrtYd")
		)
		(fp_rect
			(start -0.5842 1.3335)
			(end 0.5842 -1.3335)
			(stroke
				(width 0)
				(type default)
			)
			(fill no)
			(layer "F.Fab")
		)
		(pad "1" smd custom
			(at 0 -0.762)
			(size 0.2159 0.2159)
			(layers "F.Cu" "F.Mask" "F.Paste")
			(net "BMC_I2C5_SDA_R")
			(options
				(clearance outline)
				(anchor circle)
			)
			(primitives
				(gr_poly
					(pts
						(arc
							(start -0.3302 -0.4318)
							(mid -0.402042 -0.402042)
							(end -0.4318 -0.3302)
						)
						(arc
							(start -0.4318 0.3302)
							(mid -0.402042 0.402042)
							(end -0.3302 0.4318)
						)
						(arc
							(start 0.3302 0.4318)
							(mid 0.402042 0.402042)
							(end 0.4318 0.3302)
						)
						(arc
							(start 0.4318 -0.3302)
							(mid 0.402042 -0.402042)
							(end 0.3302 -0.4318)
						)
					)
					(width 0)
					(fill yes)
				)
			)
		)
		(pad "2" smd custom
			(at 0 0.762)
			(size 0.2159 0.2159)
			(layers "F.Cu" "F.Mask" "F.Paste")
			(net "GND")
			(options
				(clearance outline)
				(anchor circle)
			)
			(primitives
				(gr_poly
					(pts
						(arc
							(start -0.3302 -0.4318)
							(mid -0.402042 -0.402042)
							(end -0.4318 -0.3302)
						)
						(arc
							(start -0.4318 0.3302)
							(mid -0.402042 0.402042)
							(end -0.3302 0.4318)
						)
						(arc
							(start 0.3302 0.4318)
							(mid 0.402042 0.402042)
							(end 0.4318 0.3302)
						)
						(arc
							(start 0.4318 -0.3302)
							(mid 0.402042 -0.402042)
							(end 0.3302 -0.4318)
						)
					)
					(width 0)
					(fill yes)
				)
			)
		)
	)
)
